(kicad_pcb
	(version 20241229)
	(generator "pcbnew")
	(generator_version "9.0")
	(general
		(thickness 1.294)
		(legacy_teardrops no)
	)
	(paper "A3")
	(title_block
		(title "Kintex 410T devboard")
		(date "2024-04-03")
		(rev "1.1.2")
		(comment 9 "footprints 771-776 of 975")
	)
	(layers
		(0 "F.Cu" mixed)
		(4 "In1.Cu" power)
		(6 "In2.Cu" power)
		(8 "In3.Cu" mixed)
		(10 "In4.Cu" power)
		(12 "In5.Cu" mixed)
		(14 "In6.Cu" power)
		(16 "In7.Cu" mixed)
		(18 "In8.Cu" power)
		(2 "B.Cu" mixed)
		(9 "F.Adhes" user "F.Adhesive")
		(11 "B.Adhes" user "B.Adhesive")
		(13 "F.Paste" user)
		(15 "B.Paste" user)
		(5 "F.SilkS" user "F.Silkscreen")
		(7 "B.SilkS" user "B.Silkscreen")
		(1 "F.Mask" user)
		(3 "B.Mask" user)
		(17 "Dwgs.User" user "User.Drawings")
		(19 "Cmts.User" user "User.Comments")
		(21 "Eco1.User" user "User.Eco1")
		(23 "Eco2.User" user "User.Eco2")
		(25 "Edge.Cuts" user)
		(27 "Margin" user)
		(31 "F.CrtYd" user "F.Courtyard")
		(29 "B.CrtYd" user "B.Courtyard")
		(35 "F.Fab" user)
		(33 "B.Fab" user)
	)
	(footprint "antmicro-footprints:C_0201"
		(layer "B.Cu")
		(at 188.000001 122.500001 180)
		(descr "Capacitor SMD 0201")
		(tags "capacitor SMD 0201")
		(property "Reference" "C154"
			(at 2.250001 -0.399999 0)
			(layer "B.SilkS")
			(effects
				(font
					(size 0.7 0.7)
					(thickness 0.15)
				)
				(justify left bottom mirror)
			)
		)
		(property "Value" "C_100n_0201"
			(at 0 -1.4 0)
			(layer "B.Fab")
			(effects
				(font
					(size 0.7 0.7)
					(thickness 0.15)
				)
				(justify left bottom mirror)
			)
		)
		(property "Description" "SMD Multilayer Ceramic Capacitor, 0.1 µF, 6.3 V, 0201 [0603 Metric], ± 10%, X6S, CC Series"
			(at 0 0 180)
			(layer "F.Fab")
			(hide yes)
			(effects
				(font
					(size 1.27 1.27)
					(thickness 0.15)
				)
			)
		)
		(property "Author" "Antmicro"
			(at 376.000002 245.000002 0)
			(layer "B.Fab")
			(hide yes)
			(effects
				(font
					(size 1 1)
					(thickness 0.15)
				)
				(justify mirror)
			)
		)
		(property "Dielectric" ""
			(at 376.000002 245.000002 0)
			(layer "B.Fab")
			(hide yes)
			(effects
				(font
					(size 1 1)
					(thickness 0.15)
				)
				(justify mirror)
			)
		)
		(property "License" "Apache-2.0"
			(at 376.000002 245.000002 0)
			(layer "B.Fab")
			(hide yes)
			(effects
				(font
					(size 1 1)
					(thickness 0.15)
				)
				(justify mirror)
			)
		)
		(property "MPN" "CC0201KRX6S5BB104"
			(at 376.000002 245.000002 0)
			(layer "B.Fab")
			(hide yes)
			(effects
				(font
					(size 1 1)
					(thickness 0.15)
				)
				(justify mirror)
			)
		)
		(property "Manufacturer" "YAGEO"
			(at 376.000002 245.000002 0)
			(layer "B.Fab")
			(hide yes)
			(effects
				(font
					(size 1 1)
					(thickness 0.15)
				)
				(justify mirror)
			)
		)
		(property "Val" "100n"
			(at 376.000002 245.000002 0)
			(layer "B.Fab")
			(hide yes)
			(effects
				(font
					(size 1 1)
					(thickness 0.15)
				)
				(justify mirror)
			)
		)
		(property "Voltage" ""
			(at 376.000002 245.000002 0)
			(layer "B.Fab")
			(hide yes)
			(effects
				(font
					(size 1 1)
					(thickness 0.15)
				)
				(justify mirror)
			)
		)
		(sheetname "FPGA supply")
		(sheetfile "fpga-supply.kicad_sch")
		(attr smd)
		(fp_rect
			(start -0.7 0.35)
			(end 0.7 -0.35)
			(stroke
				(width 0.05)
				(type default)
			)
			(fill no)
			(layer "B.CrtYd")
		)
		(fp_rect
			(start 0.3 -0.15)
			(end -0.301 0.149)
			(stroke
				(width 0.15)
				(type solid)
			)
			(fill no)
			(layer "B.Fab")
		)
		(pad "" smd roundrect
			(at -0.349 0.002 180)
			(size 0.318 0.36)
			(layers "B.Paste")
			(roundrect_rratio 0.25)
		)
		(pad "" smd roundrect
			(at 0.341 0.002 180)
			(size 0.318 0.36)
			(layers "B.Paste")
			(roundrect_rratio 0.25)
		)
		(pad "1" smd roundrect
			(at -0.321 0.002 180)
			(size 0.46 0.4)
			(layers "B.Cu" "B.Mask")
			(roundrect_rratio 0.25)
			(net 1 "GND")
			(pintype "passive")
		)
		(pad "2" smd roundrect
			(at 0.32 0.002 180)
			(size 0.46 0.4)
			(layers "B.Cu" "B.Mask")
			(roundrect_rratio 0.25)
			(net 8 "+1V2_MGTAVTT")
			(pintype "passive")
		)
	)
	(footprint "antmicro-footprints:C_0402_1005Metric"
		(layer "B.Cu")
		(at 224.8 78.7)
		(descr "Capacitor SMD 0402")
		(tags "capacitor SMD 0402")
		(property "Reference" "C214"
			(at -1.35 -0.5 0)
			(layer "B.SilkS")
			(effects
				(font
					(size 0.7 0.7)
					(thickness 0.15)
				)
				(justify right bottom mirror)
			)
		)
		(property "Value" "C_1u_0402"
			(at 0 -1.4 0)
			(layer "B.Fab")
			(effects
				(font
					(size 0.7 0.7)
					(thickness 0.15)
				)
				(justify right bottom mirror)
			)
		)
		(property "Description" "SMD Multilayer Ceramic Capacitor, 1 µF, 10 V, 0402 [1005 Metric], ± 10%, X6S, C"
			(at 0 0 0)
			(layer "F.Fab")
			(hide yes)
			(effects
				(font
					(size 1.27 1.27)
					(thickness 0.15)
				)
			)
		)
		(property "Author" "Antmicro"
			(at 0 0 0)
			(layer "B.Fab")
			(hide yes)
			(effects
				(font
					(size 1 1)
					(thickness 0.15)
				)
				(justify mirror)
			)
		)
		(property "Dielectric" ""
			(at 0 0 0)
			(layer "B.Fab")
			(hide yes)
			(effects
				(font
					(size 1 1)
					(thickness 0.15)
				)
				(justify mirror)
			)
		)
		(property "License" "Apache-2.0"
			(at 0 0 0)
			(layer "B.Fab")
			(hide yes)
			(effects
				(font
					(size 1 1)
					(thickness 0.15)
				)
				(justify mirror)
			)
		)
		(property "MPN" "C1005X6S1A105K050BC"
			(at 0 0 0)
			(layer "B.Fab")
			(hide yes)
			(effects
				(font
					(size 1 1)
					(thickness 0.15)
				)
				(justify mirror)
			)
		)
		(property "Manufacturer" "TDK"
			(at 0 0 0)
			(layer "B.Fab")
			(hide yes)
			(effects
				(font
					(size 1 1)
					(thickness 0.15)
				)
				(justify mirror)
			)
		)
		(property "Val" "1u"
			(at 0 0 0)
			(layer "B.Fab")
			(hide yes)
			(effects
				(font
					(size 1 1)
					(thickness 0.15)
				)
				(justify mirror)
			)
		)
		(property "Voltage" ""
			(at 0 0 0)
			(layer "B.Fab")
			(hide yes)
			(effects
				(font
					(size 1 1)
					(thickness 0.15)
				)
				(justify mirror)
			)
		)
		(sheetname "User GPIO + LED + button + DIP switch")
		(sheetfile "user-gpio.kicad_sch")
		(attr smd)
		(fp_rect
			(start -0.925 0.47)
			(end 0.925 -0.47)
			(stroke
				(width 0.05)
				(type default)
			)
			(fill no)
			(layer "B.CrtYd")
		)
		(fp_line
			(start -0.494 -0.248)
			(end -0.494 0.25)
			(stroke
				(width 0.15)
				(type solid)
			)
			(layer "B.Fab")
		)
		(fp_line
			(start -0.494 0.25)
			(end 0.504 0.25)
			(stroke
				(width 0.15)
				(type solid)
			)
			(layer "B.Fab")
		)
		(fp_line
			(start 0.504 -0.248)
			(end -0.494 -0.248)
			(stroke
				(width 0.15)
				(type solid)
			)
			(layer "B.Fab")
		)
		(fp_line
			(start 0.504 0.25)
			(end 0.504 -0.248)
			(stroke
				(width 0.15)
				(type solid)
			)
			(layer "B.Fab")
		)
		(pad "1" smd roundrect
			(at -0.48 0)
			(size 0.59 0.64)
			(layers "B.Cu" "B.Mask" "B.Paste")
			(roundrect_rratio 0.25)
			(net 1 "GND")
			(pintype "passive")
		)
		(pad "2" smd roundrect
			(at 0.48 0)
			(size 0.59 0.64)
			(layers "B.Cu" "B.Mask" "B.Paste")
			(roundrect_rratio 0.25)
			(net 24 "+3V3")
			(pintype "passive")
		)
	)
	(footprint "antmicro-footprints:R_0402_1005Metric_EIA"
		(layer "B.Cu")
		(at 189 137.5)
		(descr "Resistor SMD 0402 (1005 Metric), square (rectangular) end terminal, IPC_7351 nominal, (Body size source: IPC-SM-782 page 76, https://www.pcb-3d.com/wordpress/wp-content/uploads/ipc-sm-782a_amendment_1_and_2.pdf)")
		(tags "resistor 0402")
		(property "Reference" "R339"
			(at -0.1 -1.45 180)
			(layer "B.SilkS")
			(effects
				(font
					(size 0.7 0.7)
					(thickness 0.15)
				)
				(justify left bottom mirror)
			)
		)
		(property "Value" "R_80R6_0402_EIA"
			(at 0 -1.169 180)
			(layer "B.Fab")
			(effects
				(font
					(size 0.7 0.7)
					(thickness 0.15)
				)
				(justify left bottom mirror)
			)
		)
		(property "Description" "SMD Chip Resistor, 80.6 ohm, ± 1%, 62.5 mW, 0402 [1005 Metric], Thick Film, General Purpose"
			(at 0 0 0)
			(layer "F.Fab")
			(hide yes)
			(effects
				(font
					(size 1.27 1.27)
					(thickness 0.15)
				)
			)
		)
		(property "Author" "Antmicro"
			(at 0 0 0)
			(layer "B.Fab")
			(hide yes)
			(effects
				(font
					(size 1 1)
					(thickness 0.15)
				)
				(justify mirror)
			)
		)
		(property "License" "Apache-2.0"
			(at 0 0 0)
			(layer "B.Fab")
			(hide yes)
			(effects
				(font
					(size 1 1)
					(thickness 0.15)
				)
				(justify mirror)
			)
		)
		(property "MPN" "MC00625W0402180R6"
			(at 0 0 0)
			(layer "B.Fab")
			(hide yes)
			(effects
				(font
					(size 1 1)
					(thickness 0.15)
				)
				(justify mirror)
			)
		)
		(property "Manufacturer" "Multicomp Pro"
			(at 0 0 0)
			(layer "B.Fab")
			(hide yes)
			(effects
				(font
					(size 1 1)
					(thickness 0.15)
				)
				(justify mirror)
			)
		)
		(property "Tolerance" "1%"
			(at 0 0 0)
			(layer "B.Fab")
			(hide yes)
			(effects
				(font
					(size 1 1)
					(thickness 0.15)
				)
				(justify mirror)
			)
		)
		(property "Val" "80R6"
			(at 0 0 0)
			(layer "B.Fab")
			(hide yes)
			(effects
				(font
					(size 1 1)
					(thickness 0.15)
				)
				(justify mirror)
			)
		)
		(sheetname "FPGA Bank 33 & 34")
		(sheetfile "fpga-bank-33-34.kicad_sch")
		(attr smd)
		(fp_rect
			(start -0.95 0.45)
			(end 0.95 -0.45)
			(stroke
				(width 0.05)
				(type default)
			)
			(fill no)
			(layer "B.CrtYd")
		)
		(fp_line
			(start -0.5 -0.249)
			(end -0.5 0.25)
			(stroke
				(width 0.15)
				(type solid)
			)
			(layer "B.Fab")
		)
		(fp_line
			(start -0.5 0.25)
			(end 0.499 0.25)
			(stroke
				(width 0.15)
				(type solid)
			)
			(layer "B.Fab")
		)
		(fp_line
			(start 0.499 -0.249)
			(end -0.5 -0.249)
			(stroke
				(width 0.15)
				(type solid)
			)
			(layer "B.Fab")
		)
		(fp_line
			(start 0.499 0.25)
			(end 0.499 -0.249)
			(stroke
				(width 0.15)
				(type solid)
			)
			(layer "B.Fab")
		)
		(pad "1" smd roundrect
			(at -0.5 0 270)
			(size 0.6 0.6)
			(layers "B.Cu" "B.Mask" "B.Paste")
			(roundrect_rratio 0.25)
			(net 1 "GND")
			(pintype "passive")
		)
		(pad "2" smd roundrect
			(at 0.499 0)
			(size 0.6 0.6)
			(layers "B.Cu" "B.Mask" "B.Paste")
			(roundrect_rratio 0.25)
			(net 567 "/FPGA Bank 33 & 34/DDR_VRN")
			(pintype "passive")
		)
	)
	(footprint "antmicro-footprints:R_0402_1005Metric"
		(layer "B.Cu")
		(at 212.899999 77.899999 90)
		(descr "Resistor SMD 0402")
		(tags "resistor SMD 0402")
		(property "Reference" "R112"
			(at 3.599999 0.350001 90)
			(layer "B.SilkS")
			(effects
				(font
					(size 0.7 0.7)
					(thickness 0.15)
				)
				(justify left bottom mirror)
			)
		)
		(property "Value" "R_100R_0402"
			(at 0 -1.4 270)
			(layer "B.Fab")
			(effects
				(font
					(size 0.7 0.7)
					(thickness 0.15)
				)
				(justify left bottom mirror)
			)
		)
		(property "Description" "SMD Chip Resistor, 100 ohm, ± 1%, 62.5 mW, 0402 [1005 Metric], Thick Film, General Purpose"
			(at 0 0 90)
			(layer "F.Fab")
			(hide yes)
			(effects
				(font
					(size 1.27 1.27)
					(thickness 0.15)
				)
			)
		)
		(property "Author" "Antmicro"
			(at 290.799998 -135 0)
			(layer "B.Fab")
			(hide yes)
			(effects
				(font
					(size 1 1)
					(thickness 0.15)
				)
				(justify mirror)
			)
		)
		(property "License" "Apache-2.0"
			(at 290.799998 -135 0)
			(layer "B.Fab")
			(hide yes)
			(effects
				(font
					(size 1 1)
					(thickness 0.15)
				)
				(justify mirror)
			)
		)
		(property "MPN" "CR0402-FX-1000GLF"
			(at 290.799998 -135 0)
			(layer "B.Fab")
			(hide yes)
			(effects
				(font
					(size 1 1)
					(thickness 0.15)
				)
				(justify mirror)
			)
		)
		(property "Manufacturer" "Bourns"
			(at 290.799998 -135 0)
			(layer "B.Fab")
			(hide yes)
			(effects
				(font
					(size 1 1)
					(thickness 0.15)
				)
				(justify mirror)
			)
		)
		(property "Tolerance" "1%"
			(at 290.799998 -135 0)
			(layer "B.Fab")
			(hide yes)
			(effects
				(font
					(size 1 1)
					(thickness 0.15)
				)
				(justify mirror)
			)
		)
		(property "Val" "100R"
			(at 290.799998 -135 0)
			(layer "B.Fab")
			(hide yes)
			(effects
				(font
					(size 1 1)
					(thickness 0.15)
				)
				(justify mirror)
			)
		)
		(sheetname "User GPIO + LED + button + DIP switch")
		(sheetfile "user-gpio.kicad_sch")
		(attr smd)
		(fp_rect
			(start -0.925 0.47)
			(end 0.925 -0.47)
			(stroke
				(width 0.05)
				(type default)
			)
			(fill no)
			(layer "B.CrtYd")
		)
		(fp_rect
			(start -0.5 0.25)
			(end 0.5 -0.25)
			(stroke
				(width 0.15)
				(type solid)
			)
			(fill no)
			(layer "B.Fab")
		)
		(pad "1" smd roundrect
			(at -0.48 0 90)
			(size 0.59 0.64)
			(layers "B.Cu" "B.Mask" "B.Paste")
			(roundrect_rratio 0.25)
			(net 808 "/User GPIO + LED + button + DIP switch/PMOD_A_7")
			(pintype "passive")
		)
		(pad "2" smd roundrect
			(at 0.48 0 90)
			(size 0.59 0.64)
			(layers "B.Cu" "B.Mask" "B.Paste")
			(roundrect_rratio 0.25)
			(net 433 "/FPGA Bank 12 & 13/PMOD_A.IO7")
			(pintype "passive")
		)
	)
	(footprint "antmicro-footprints:C_0201"
		(layer "B.Cu")
		(at 201.5 125.65)
		(descr "Capacitor SMD 0201")
		(tags "capacitor SMD 0201")
		(property "Reference" "C28"
			(at 24.775 -29.675 0)
			(layer "B.SilkS")
			(effects
				(font
					(size 0.7 0.7)
					(thickness 0.15)
				)
				(justify right bottom mirror)
			)
		)
		(property "Value" "C_4u7_0201"
			(at 0 -1.4 0)
			(layer "B.Fab")
			(effects
				(font
					(size 0.7 0.7)
					(thickness 0.15)
				)
				(justify right bottom mirror)
			)
		)
		(property "Description" "SMD Multilayer Ceramic Capacitor, 4.7 µF, 6.3 V, 0201 [0603 Metric], ± 20%, X5R, GRM Series"
			(at 0 0 0)
			(layer "F.Fab")
			(hide yes)
			(effects
				(font
					(size 1.27 1.27)
					(thickness 0.15)
				)
			)
		)
		(property "Author" "Antmicro"
			(at 0 0 0)
			(layer "B.Fab")
			(hide yes)
			(effects
				(font
					(size 1 1)
					(thickness 0.15)
				)
				(justify mirror)
			)
		)
		(property "Dielectric" ""
			(at 0 0 0)
			(layer "B.Fab")
			(hide yes)
			(effects
				(font
					(size 1 1)
					(thickness 0.15)
				)
				(justify mirror)
			)
		)
		(property "License" "Apache-2.0"
			(at 0 0 0)
			(layer "B.Fab")
			(hide yes)
			(effects
				(font
					(size 1 1)
					(thickness 0.15)
				)
				(justify mirror)
			)
		)
		(property "MPN" "GRM035R60J475ME15D"
			(at 0 0 0)
			(layer "B.Fab")
			(hide yes)
			(effects
				(font
					(size 1 1)
					(thickness 0.15)
				)
				(justify mirror)
			)
		)
		(property "Manufacturer" "Murata"
			(at 0 0 0)
			(layer "B.Fab")
			(hide yes)
			(effects
				(font
					(size 1 1)
					(thickness 0.15)
				)
				(justify mirror)
			)
		)
		(property "Val" "4u7"
			(at 0 0 0)
			(layer "B.Fab")
			(hide yes)
			(effects
				(font
					(size 1 1)
					(thickness 0.15)
				)
				(justify mirror)
			)
		)
		(property "Voltage" ""
			(at 0 0 0)
			(layer "B.Fab")
			(hide yes)
			(effects
				(font
					(size 1 1)
					(thickness 0.15)
				)
				(justify mirror)
			)
		)
		(sheetname "FPGA supply")
		(sheetfile "fpga-supply.kicad_sch")
		(attr smd)
		(fp_rect
			(start -0.7 0.35)
			(end 0.7 -0.35)
			(stroke
				(width 0.05)
				(type default)
			)
			(fill no)
			(layer "B.CrtYd")
		)
		(fp_rect
			(start 0.3 -0.15)
			(end -0.301 0.149)
			(stroke
				(width 0.15)
				(type solid)
			)
			(fill no)
			(layer "B.Fab")
		)
		(pad "" smd roundrect
			(at -0.349 0.002)
			(size 0.318 0.36)
			(layers "B.Paste")
			(roundrect_rratio 0.25)
		)
		(pad "" smd roundrect
			(at 0.341 0.002)
			(size 0.318 0.36)
			(layers "B.Paste")
			(roundrect_rratio 0.25)
		)
		(pad "1" smd roundrect
			(at -0.321 0.002)
			(size 0.46 0.4)
			(layers "B.Cu" "B.Mask")
			(roundrect_rratio 0.25)
			(net 1 "GND")
			(pintype "passive")
		)
		(pad "2" smd roundrect
			(at 0.32 0.002)
			(size 0.46 0.4)
			(layers "B.Cu" "B.Mask")
			(roundrect_rratio 0.25)
			(net 650 "+1V0")
			(pintype "passive")
		)
	)
	(footprint "antmicro-footprints:C_0402_1005Metric"
		(layer "B.Cu")
		(at 254.801 166.8 90)
		(descr "Capacitor SMD 0402")
		(tags "capacitor SMD 0402")
		(property "Reference" "C279"
			(at -1.9 -1.576 90)
			(layer "B.SilkS")
			(effects
				(font
					(size 0.7 0.7)
					(thickness 0.15)
				)
				(justify right bottom mirror)
			)
		)
		(property "Value" "C_10p_0402"
			(at 0 -1.4 90)
			(layer "B.Fab")
			(effects
				(font
					(size 0.7 0.7)
					(thickness 0.15)
				)
				(justify right bottom mirror)
			)
		)
		(property "Description" "SMD Multilayer Ceramic Capacitor, 10 pF, 50 V, 0402 [1005 Metric], ± 2%, C0G / NP0, GCM"
			(at 0 0 90)
			(layer "F.Fab")
			(hide yes)
			(effects
				(font
					(size 1.27 1.27)
					(thickness 0.15)
				)
			)
		)
		(property "Author" "Antmicro"
			(at 421.601 -88.001 0)
			(layer "B.Fab")
			(hide yes)
			(effects
				(font
					(size 1 1)
					(thickness 0.15)
				)
				(justify mirror)
			)
		)
		(property "Dielectric" "C0G"
			(at 421.601 -88.001 0)
			(layer "B.Fab")
			(hide yes)
			(effects
				(font
					(size 1 1)
					(thickness 0.15)
				)
				(justify mirror)
			)
		)
		(property "License" "Apache-2.0"
			(at 421.601 -88.001 0)
			(layer "B.Fab")
			(hide yes)
			(effects
				(font
					(size 1 1)
					(thickness 0.15)
				)
				(justify mirror)
			)
		)
		(property "MPN" "GCM1555C1H100GA16D"
			(at 421.601 -88.001 0)
			(layer "B.Fab")
			(hide yes)
			(effects
				(font
					(size 1 1)
					(thickness 0.15)
				)
				(justify mirror)
			)
		)
		(property "Manufacturer" "Murata"
			(at 421.601 -88.001 0)
			(layer "B.Fab")
			(hide yes)
			(effects
				(font
					(size 1 1)
					(thickness 0.15)
				)
				(justify mirror)
			)
		)
		(property "Val" "10p"
			(at 421.601 -88.001 0)
			(layer "B.Fab")
			(hide yes)
			(effects
				(font
					(size 1 1)
					(thickness 0.15)
				)
				(justify mirror)
			)
		)
		(property "Voltage" "50V"
			(at 421.601 -88.001 0)
			(layer "B.Fab")
			(hide yes)
			(effects
				(font
					(size 1 1)
					(thickness 0.15)
				)
				(justify mirror)
			)
		)
		(sheetname "HDMI + Ethernet")
		(sheetfile "hdmi-ethernet.kicad_sch")
		(attr smd)
		(fp_rect
			(start -0.925 0.47)
			(end 0.925 -0.47)
			(stroke
				(width 0.05)
				(type default)
			)
			(fill no)
			(layer "B.CrtYd")
		)
		(fp_line
			(start 0.504 -0.248)
			(end -0.494 -0.248)
			(stroke
				(width 0.15)
				(type solid)
			)
			(layer "B.Fab")
		)
		(fp_line
			(start -0.494 -0.248)
			(end -0.494 0.25)
			(stroke
				(width 0.15)
				(type solid)
			)
			(layer "B.Fab")
		)
		(fp_line
			(start 0.504 0.25)
			(end 0.504 -0.248)
			(stroke
				(width 0.15)
				(type solid)
			)
			(layer "B.Fab")
		)
		(fp_line
			(start -0.494 0.25)
			(end 0.504 0.25)
			(stroke
				(width 0.15)
				(type solid)
			)
			(layer "B.Fab")
		)
		(pad "1" smd roundrect
			(at -0.48 0 90)
			(size 0.59 0.64)
			(layers "B.Cu" "B.Mask" "B.Paste")
			(roundrect_rratio 0.25)
			(net 1 "GND")
			(pintype "passive")
		)
		(pad "2" smd roundrect
			(at 0.48 0 90)
			(size 0.59 0.64)
			(layers "B.Cu" "B.Mask" "B.Paste")
			(roundrect_rratio 0.25)
			(net 729 "/HDMI + Ethernet/ETH2_N")
			(pintype "passive")
		)
	)
)
